(kicad_pcb
	(version 20260206)
	(generator "pcbnew")
	(generator_version "10.0")
	(general
		(thickness 1.6)
		(legacy_teardrops no)
	)
	(paper "A4")
	(title_block
		(title "fcb — Lightning_FCB_BRD.brd")
		(comment 1 "Lightning (Wiwynn / Facebook NVMe JBOF) / footprints 384-391 of 495")
	)
	(layers
		(0 "F.Cu" signal "TOP")
		(4 "In1.Cu" signal "L2GND")
		(6 "In2.Cu" signal "L3VCC")
		(2 "B.Cu" signal "BOTTOM")
		(9 "F.Adhes" user "F.Adhesive")
		(11 "B.Adhes" user "B.Adhesive")
		(13 "F.Paste" user "Package Geometry/Pastemask Top")
		(15 "B.Paste" user "Package Geometry/Pastemask Bottom")
		(5 "F.SilkS" user "Ref Des/Silkscreen Top")
		(7 "B.SilkS" user "Ref Des/Silkscreen Bottom")
		(1 "F.Mask" user "Board Geometry/Soldermask Top")
		(3 "B.Mask" user "Board Geometry/Soldermask Bottom")
		(17 "Dwgs.User" user "User.Drawings")
		(19 "Cmts.User" user "User.Comments")
		(21 "Eco1.User" user "User.Eco1")
		(23 "Eco2.User" user "User.Eco2")
		(25 "Edge.Cuts" user "Board Geometry/Outline")
		(27 "Margin" user)
		(31 "F.CrtYd" user "Package Geometry/Place Bound Top")
		(29 "B.CrtYd" user "Package Geometry/Place Bound Bottom")
		(35 "F.Fab" user "Ref Des/Assembly Top")
		(33 "B.Fab" user "Ref Des/Assembly Bottom")
	)
	(footprint ""
		(layer "F.Cu")
		(at 36.1188 -371.4496 -90)
		(property "Reference" "PR6"
			(at 0 0 270)
			(layer "F.SilkS")
			(hide yes)
			(effects
				(font
					(size 1.27 1.27)
				)
			)
		)
		(property "Value" "100KR2F-L1-GP"
			(at 0.064008 -3.993896 270)
			(unlocked yes)
			(layer "F.Fab")
			(hide yes)
			(effects
				(font
					(size 1.016 1.016)
					(thickness 0.1524)
				)
			)
		)
		(property "Device Type" "R402H16"
			(at 0.064008 -5.517896 270)
			(unlocked yes)
			(layer "F.Fab")
			(hide yes)
			(effects
				(font
					(size 1.016 1.016)
					(thickness 0.1524)
				)
			)
		)
		(duplicate_pad_numbers_are_jumpers no)
		(fp_line
			(start -0.508 -0.9398)
			(end -0.508 0.9398)
			(stroke
				(width 0.1524)
				(type default)
			)
			(layer "F.SilkS")
		)
		(fp_line
			(start 0.508 -0.9398)
			(end -0.508 -0.9398)
			(stroke
				(width 0.1524)
				(type default)
			)
			(layer "F.SilkS")
		)
		(fp_rect
			(start -0.508 0.9398)
			(end 0.508 -0.9398)
			(stroke
				(width 0)
				(type default)
			)
			(fill no)
			(layer "F.CrtYd")
		)
		(fp_rect
			(start -0.508 0.9398)
			(end 0.508 -0.9398)
			(stroke
				(width 0)
				(type default)
			)
			(fill no)
			(layer "F.Fab")
		)
		(pad "1" smd custom
			(at 0 -0.4445 270)
			(size 0.1397 0.1397)
			(layers "F.Cu" "F.Mask" "F.Paste")
			(net "P12V")
			(options
				(clearance outline)
				(anchor circle)
			)
			(primitives
				(gr_poly
					(pts
						(arc
							(start -0.1778 -0.2794)
							(mid -0.249642 -0.249642)
							(end -0.2794 -0.1778)
						)
						(arc
							(start -0.2794 0.1778)
							(mid -0.249642 0.249642)
							(end -0.1778 0.2794)
						)
						(arc
							(start 0.1778 0.2794)
							(mid 0.249642 0.249642)
							(end 0.2794 0.1778)
						)
						(arc
							(start 0.2794 -0.1778)
							(mid 0.249642 -0.249642)
							(end 0.1778 -0.2794)
						)
					)
					(width 0)
					(fill yes)
				)
			)
		)
		(pad "2" smd custom
			(at 0 0.4445 270)
			(size 0.1397 0.1397)
			(layers "F.Cu" "F.Mask" "F.Paste")
			(net "ADM1276_FLB")
			(options
				(clearance outline)
				(anchor circle)
			)
			(primitives
				(gr_poly
					(pts
						(arc
							(start -0.1778 -0.2794)
							(mid -0.249642 -0.249642)
							(end -0.2794 -0.1778)
						)
						(arc
							(start -0.2794 0.1778)
							(mid -0.249642 0.249642)
							(end -0.1778 0.2794)
						)
						(arc
							(start 0.1778 0.2794)
							(mid 0.249642 0.249642)
							(end 0.2794 0.1778)
						)
						(arc
							(start 0.2794 -0.1778)
							(mid 0.249642 -0.249642)
							(end 0.1778 -0.2794)
						)
					)
					(width 0)
					(fill yes)
				)
			)
		)
	)
	(footprint ""
		(layer "F.Cu")
		(at 12.2428 -54.2036 90)
		(property "Reference" "R62"
			(at 0 0 90)
			(layer "F.SilkS")
			(hide yes)
			(effects
				(font
					(size 1.27 1.27)
				)
			)
		)
		(property "Value" "0R2J-2-GP"
			(at 0.064008 -3.993896 90)
			(unlocked yes)
			(layer "F.Fab")
			(hide yes)
			(effects
				(font
					(size 1.016 1.016)
					(thickness 0.1524)
				)
			)
		)
		(property "Device Type" "R402H16"
			(at 0.064008 -5.517896 90)
			(unlocked yes)
			(layer "F.Fab")
			(hide yes)
			(effects
				(font
					(size 1.016 1.016)
					(thickness 0.1524)
				)
			)
		)
		(duplicate_pad_numbers_are_jumpers no)
		(fp_line
			(start 0.508 -0.9398)
			(end -0.508 -0.9398)
			(stroke
				(width 0.1524)
				(type default)
			)
			(layer "F.SilkS")
		)
		(fp_line
			(start -0.508 -0.9398)
			(end -0.508 0.9398)
			(stroke
				(width 0.1524)
				(type default)
			)
			(layer "F.SilkS")
		)
		(fp_rect
			(start -0.508 0.9398)
			(end 0.508 -0.9398)
			(stroke
				(width 0)
				(type default)
			)
			(fill no)
			(layer "F.CrtYd")
		)
		(fp_rect
			(start -0.508 0.9398)
			(end 0.508 -0.9398)
			(stroke
				(width 0)
				(type default)
			)
			(fill no)
			(layer "F.Fab")
		)
		(pad "1" smd custom
			(at 0 -0.4445 90)
			(size 0.1397 0.1397)
			(layers "F.Cu" "F.Mask" "F.Paste")
			(net "SELF_TRAY_PRESENT_UPPER")
			(options
				(clearance outline)
				(anchor circle)
			)
			(primitives
				(gr_poly
					(pts
						(arc
							(start -0.1778 -0.2794)
							(mid -0.249642 -0.249642)
							(end -0.2794 -0.1778)
						)
						(arc
							(start -0.2794 0.1778)
							(mid -0.249642 0.249642)
							(end -0.1778 0.2794)
						)
						(arc
							(start 0.1778 0.2794)
							(mid 0.249642 0.249642)
							(end 0.2794 0.1778)
						)
						(arc
							(start 0.2794 -0.1778)
							(mid 0.249642 -0.249642)
							(end 0.1778 -0.2794)
						)
					)
					(width 0)
					(fill yes)
				)
			)
		)
		(pad "2" smd custom
			(at 0 0.4445 90)
			(size 0.1397 0.1397)
			(layers "F.Cu" "F.Mask" "F.Paste")
			(net "PEER_TRAY PRESENT_LOWER")
			(options
				(clearance outline)
				(anchor circle)
			)
			(primitives
				(gr_poly
					(pts
						(arc
							(start -0.1778 -0.2794)
							(mid -0.249642 -0.249642)
							(end -0.2794 -0.1778)
						)
						(arc
							(start -0.2794 0.1778)
							(mid -0.249642 0.249642)
							(end -0.1778 0.2794)
						)
						(arc
							(start 0.1778 0.2794)
							(mid 0.249642 0.249642)
							(end 0.2794 0.1778)
						)
						(arc
							(start 0.2794 -0.1778)
							(mid 0.249642 -0.249642)
							(end 0.1778 -0.2794)
						)
					)
					(width 0)
					(fill yes)
				)
			)
		)
	)
	(footprint ""
		(layer "F.Cu")
		(at 9.4488 -64.8208 180)
		(property "Reference" "R26"
			(at 0 0 180)
			(layer "F.SilkS")
			(hide yes)
			(effects
				(font
					(size 1.27 1.27)
				)
			)
		)
		(property "Value" "0R2J-2-GP"
			(at 0.064008 -3.993896 180)
			(unlocked yes)
			(layer "F.Fab")
			(hide yes)
			(effects
				(font
					(size 1.016 1.016)
					(thickness 0.1524)
				)
			)
		)
		(property "Device Type" "R402H16"
			(at 0.064008 -5.517896 180)
			(unlocked yes)
			(layer "F.Fab")
			(hide yes)
			(effects
				(font
					(size 1.016 1.016)
					(thickness 0.1524)
				)
			)
		)
		(duplicate_pad_numbers_are_jumpers no)
		(fp_line
			(start 0.508 -0.9398)
			(end -0.508 -0.9398)
			(stroke
				(width 0.1524)
				(type default)
			)
			(layer "F.SilkS")
		)
		(fp_line
			(start -0.508 -0.9398)
			(end -0.508 0.9398)
			(stroke
				(width 0.1524)
				(type default)
			)
			(layer "F.SilkS")
		)
		(fp_rect
			(start -0.508 0.9398)
			(end 0.508 -0.9398)
			(stroke
				(width 0)
				(type default)
			)
			(fill no)
			(layer "F.CrtYd")
		)
		(fp_rect
			(start -0.508 0.9398)
			(end 0.508 -0.9398)
			(stroke
				(width 0)
				(type default)
			)
			(fill no)
			(layer "F.Fab")
		)
		(pad "1" smd custom
			(at 0 -0.4445 180)
			(size 0.1397 0.1397)
			(layers "F.Cu" "F.Mask" "F.Paste")
			(net "LED_DR_LED5_K")
			(options
				(clearance outline)
				(anchor circle)
			)
			(primitives
				(gr_poly
					(pts
						(arc
							(start -0.1778 -0.2794)
							(mid -0.249642 -0.249642)
							(end -0.2794 -0.1778)
						)
						(arc
							(start -0.2794 0.1778)
							(mid -0.249642 0.249642)
							(end -0.1778 0.2794)
						)
						(arc
							(start 0.1778 0.2794)
							(mid 0.249642 0.249642)
							(end 0.2794 0.1778)
						)
						(arc
							(start 0.2794 -0.1778)
							(mid 0.249642 -0.249642)
							(end 0.1778 -0.2794)
						)
					)
					(width 0)
					(fill yes)
				)
			)
		)
		(pad "2" smd custom
			(at 0 0.4445 180)
			(size 0.1397 0.1397)
			(layers "F.Cu" "F.Mask" "F.Paste")
			(net "GND")
			(options
				(clearance outline)
				(anchor circle)
			)
			(primitives
				(gr_poly
					(pts
						(arc
							(start -0.1778 -0.2794)
							(mid -0.249642 -0.249642)
							(end -0.2794 -0.1778)
						)
						(arc
							(start -0.2794 0.1778)
							(mid -0.249642 0.249642)
							(end -0.1778 0.2794)
						)
						(arc
							(start 0.1778 0.2794)
							(mid 0.249642 0.249642)
							(end 0.2794 0.1778)
						)
						(arc
							(start 0.2794 -0.1778)
							(mid 0.249642 -0.249642)
							(end 0.1778 -0.2794)
						)
					)
					(width 0)
					(fill yes)
				)
			)
		)
	)
	(footprint ""
		(layer "F.Cu")
		(at 5.5626 -429.9712 90)
		(property "Reference" "R31"
			(at 0 0 90)
			(layer "F.SilkS")
			(hide yes)
			(effects
				(font
					(size 1.27 1.27)
				)
			)
		)
		(property "Value" "33R2F-3-GP"
			(at 0.064008 -3.993896 90)
			(unlocked yes)
			(layer "F.Fab")
			(hide yes)
			(effects
				(font
					(size 1.016 1.016)
					(thickness 0.1524)
				)
			)
		)
		(property "Device Type" "R402H16"
			(at 0.064008 -5.517896 90)
			(unlocked yes)
			(layer "F.Fab")
			(hide yes)
			(effects
				(font
					(size 1.016 1.016)
					(thickness 0.1524)
				)
			)
		)
		(duplicate_pad_numbers_are_jumpers no)
		(fp_line
			(start 0.508 -0.9398)
			(end -0.508 -0.9398)
			(stroke
				(width 0.1524)
				(type default)
			)
			(layer "F.SilkS")
		)
		(fp_line
			(start -0.508 -0.9398)
			(end -0.508 0.9398)
			(stroke
				(width 0.1524)
				(type default)
			)
			(layer "F.SilkS")
		)
		(fp_rect
			(start -0.508 0.9398)
			(end 0.508 -0.9398)
			(stroke
				(width 0)
				(type default)
			)
			(fill no)
			(layer "F.CrtYd")
		)
		(fp_rect
			(start -0.508 0.9398)
			(end 0.508 -0.9398)
			(stroke
				(width 0)
				(type default)
			)
			(fill no)
			(layer "F.Fab")
		)
		(pad "1" smd custom
			(at 0 -0.4445 90)
			(size 0.1397 0.1397)
			(layers "F.Cu" "F.Mask" "F.Paste")
			(net "P3V3")
			(options
				(clearance outline)
				(anchor circle)
			)
			(primitives
				(gr_poly
					(pts
						(arc
							(start -0.1778 -0.2794)
							(mid -0.249642 -0.249642)
							(end -0.2794 -0.1778)
						)
						(arc
							(start -0.2794 0.1778)
							(mid -0.249642 0.249642)
							(end -0.1778 0.2794)
						)
						(arc
							(start 0.1778 0.2794)
							(mid 0.249642 0.249642)
							(end 0.2794 0.1778)
						)
						(arc
							(start 0.2794 -0.1778)
							(mid 0.249642 -0.249642)
							(end 0.1778 -0.2794)
						)
					)
					(width 0)
					(fill yes)
				)
			)
		)
		(pad "2" smd custom
			(at 0 0.4445 90)
			(size 0.1397 0.1397)
			(layers "F.Cu" "F.Mask" "F.Paste")
			(net "LED_DR_LED0_BLUE")
			(options
				(clearance outline)
				(anchor circle)
			)
			(primitives
				(gr_poly
					(pts
						(arc
							(start -0.1778 -0.2794)
							(mid -0.249642 -0.249642)
							(end -0.2794 -0.1778)
						)
						(arc
							(start -0.2794 0.1778)
							(mid -0.249642 0.249642)
							(end -0.1778 0.2794)
						)
						(arc
							(start 0.1778 0.2794)
							(mid 0.249642 0.249642)
							(end 0.2794 0.1778)
						)
						(arc
							(start 0.2794 -0.1778)
							(mid 0.249642 -0.249642)
							(end 0.1778 -0.2794)
						)
					)
					(width 0)
					(fill yes)
				)
			)
		)
	)
	(footprint ""
		(layer "F.Cu")
		(at 36.068 -252.603 -90)
		(property "Reference" "TP18"
			(at 0 0 270)
			(layer "F.SilkS")
			(hide yes)
			(effects
				(font
					(size 1.27 1.27)
				)
			)
		)
		(property "Value" "TPAD32-GP"
			(at 0 -3.166364 270)
			(unlocked yes)
			(layer "F.Fab")
			(hide yes)
			(effects
				(font
					(size 1.016 1.016)
					(thickness 0.1524)
				)
			)
		)
		(property "Device Type" "TPAD32"
			(at 0 -4.690618 270)
			(unlocked yes)
			(layer "F.Fab")
			(hide yes)
			(effects
				(font
					(size 1.016 1.016)
					(thickness 0.1524)
				)
			)
		)
		(duplicate_pad_numbers_are_jumpers no)
		(fp_poly
			(pts
				(arc
					(start 0.7112 0)
					(mid -0.7112 0)
					(end 0.7112 0)
				)
			)
			(stroke
				(width 0)
				(type default)
			)
			(fill no)
			(layer "F.CrtYd")
		)
		(fp_poly
			(pts
				(arc
					(start 0.7112 0)
					(mid -0.7112 0)
					(end 0.7112 0)
				)
			)
			(stroke
				(width 0)
				(type default)
			)
			(fill no)
			(layer "F.Fab")
		)
		(pad "1" smd circle
			(at 0 0 270)
			(size 0.8128 0.8128)
			(layers "F.Cu" "F.Mask" "F.Paste")
			(net "LED_DRV_RST")
		)
	)
	(footprint ""
		(layer "F.Cu")
		(at 41.4782 -177.6222)
		(property "Reference" "C253"
			(at 0 0 0)
			(layer "F.SilkS")
			(hide yes)
			(effects
				(font
					(size 1.27 1.27)
				)
			)
		)
		(property "Value" "SC4D7U6D3V3KX-GP"
			(at 0 -2.8194 0)
			(unlocked yes)
			(layer "F.Fab")
			(hide yes)
			(effects
				(font
					(size 1.016 1.016)
					(thickness 0.1524)
				)
			)
		)
		(property "Device Type" "C603H36"
			(at 0 -4.3434 0)
			(unlocked yes)
			(layer "F.Fab")
			(hide yes)
			(effects
				(font
					(size 1.016 1.016)
					(thickness 0.1524)
				)
			)
		)
		(duplicate_pad_numbers_are_jumpers no)
		(fp_line
			(start 0.508 0)
			(end -0.508 0)
			(stroke
				(width 0.2032)
				(type default)
			)
			(layer "F.SilkS")
		)
		(fp_rect
			(start -0.5842 1.3335)
			(end 0.5842 -1.3335)
			(stroke
				(width 0)
				(type default)
			)
			(fill no)
			(layer "F.CrtYd")
		)
		(fp_rect
			(start -0.5842 1.3335)
			(end 0.5842 -1.3335)
			(stroke
				(width 0)
				(type default)
			)
			(fill no)
			(layer "F.Fab")
		)
		(pad "1" smd custom
			(at 0 -0.762)
			(size 0.2159 0.2159)
			(layers "F.Cu" "F.Mask" "F.Paste")
			(net "D_LATCH_PRE#")
			(options
				(clearance outline)
				(anchor circle)
			)
			(primitives
				(gr_poly
					(pts
						(arc
							(start -0.3302 -0.4318)
							(mid -0.402042 -0.402042)
							(end -0.4318 -0.3302)
						)
						(arc
							(start -0.4318 0.3302)
							(mid -0.402042 0.402042)
							(end -0.3302 0.4318)
						)
						(arc
							(start 0.3302 0.4318)
							(mid 0.402042 0.402042)
							(end 0.4318 0.3302)
						)
						(arc
							(start 0.4318 -0.3302)
							(mid 0.402042 -0.402042)
							(end 0.3302 -0.4318)
						)
					)
					(width 0)
					(fill yes)
				)
			)
		)
		(pad "2" smd custom
			(at 0 0.762)
			(size 0.2159 0.2159)
			(layers "F.Cu" "F.Mask" "F.Paste")
			(net "GND")
			(options
				(clearance outline)
				(anchor circle)
			)
			(primitives
				(gr_poly
					(pts
						(arc
							(start -0.3302 -0.4318)
							(mid -0.402042 -0.402042)
							(end -0.4318 -0.3302)
						)
						(arc
							(start -0.4318 0.3302)
							(mid -0.402042 0.402042)
							(end -0.3302 0.4318)
						)
						(arc
							(start 0.3302 0.4318)
							(mid 0.402042 0.402042)
							(end 0.4318 0.3302)
						)
						(arc
							(start 0.4318 -0.3302)
							(mid 0.402042 -0.402042)
							(end 0.3302 -0.4318)
						)
					)
					(width 0)
					(fill yes)
				)
			)
		)
	)
	(footprint ""
		(layer "F.Cu")
		(at 5.5118 -420.9034 90)
		(property "Reference" "R126"
			(at 0 0 90)
			(layer "F.SilkS")
			(hide yes)
			(effects
				(font
					(size 1.27 1.27)
				)
			)
		)
		(property "Value" "1K8R6J-GP"
			(at -0.0508 -4.8514 90)
			(unlocked yes)
			(layer "F.Fab")
			(hide yes)
			(effects
				(font
					(size 1.016 1.016)
					(thickness 0.1524)
				)
			)
		)
		(property "Device Type" "R1206H28"
			(at 0 -6.3754 90)
			(unlocked yes)
			(layer "F.Fab")
			(hide yes)
			(effects
				(font
					(size 1.016 1.016)
					(thickness 0.1524)
				)
			)
		)
		(duplicate_pad_numbers_are_jumpers no)
		(fp_line
			(start 1.016 -2.2352)
			(end 1.016 2.2352)
			(stroke
				(width 0.1524)
				(type default)
			)
			(layer "F.SilkS")
		)
		(fp_line
			(start -1.016 -2.2352)
			(end 1.016 -2.2352)
			(stroke
				(width 0.1524)
				(type default)
			)
			(layer "F.SilkS")
		)
		(fp_line
			(start 1.016 2.2352)
			(end -1.016 2.2352)
			(stroke
				(width 0.1524)
				(type default)
			)
			(layer "F.SilkS")
		)
		(fp_line
			(start -1.016 2.2352)
			(end -1.016 -2.2352)
			(stroke
				(width 0.1524)
				(type default)
			)
			(layer "F.SilkS")
		)
		(fp_rect
			(start -1.0922 2.3114)
			(end 1.0922 -2.3114)
			(stroke
				(width 0)
				(type default)
			)
			(fill no)
			(layer "F.CrtYd")
		)
		(fp_poly
			(pts
				(xy -1.0922 -2.3114) (xy 1.0922 -2.3114) (xy 1.0922 2.3114) (xy -1.0922 2.3114)
			)
			(stroke
				(width 0)
				(type default)
			)
			(fill no)
			(layer "F.Fab")
		)
		(pad "1" smd rect
			(at 0 -1.397 90)
			(size 1.651 1.27)
			(layers "F.Cu" "F.Mask" "F.Paste")
			(net "P12V")
		)
		(pad "2" smd rect
			(at 0 1.397 90)
			(size 1.651 1.27)
			(layers "F.Cu" "F.Mask" "F.Paste")
			(net "LED_DR_LED1_BLUE")
		)
	)
	(footprint ""
		(layer "F.Cu")
		(at 18.415 -109.5502 90)
		(property "Reference" "PR118"
			(at 0 0 90)
			(layer "F.SilkS")
			(hide yes)
			(effects
				(font
					(size 1.27 1.27)
				)
			)
		)
		(property "Value" "10R2F-L-GP"
			(at 0.064008 -3.993896 90)
			(unlocked yes)
			(layer "F.Fab")
			(hide yes)
			(effects
				(font
					(size 1.016 1.016)
					(thickness 0.1524)
				)
			)
		)
		(property "Device Type" "R402H14"
			(at 0.064008 -5.517896 90)
			(unlocked yes)
			(layer "F.Fab")
			(hide yes)
			(effects
				(font
					(size 1.016 1.016)
					(thickness 0.1524)
				)
			)
		)
		(duplicate_pad_numbers_are_jumpers no)
		(fp_line
			(start 0.508 -0.9398)
			(end -0.508 -0.9398)
			(stroke
				(width 0.1524)
				(type default)
			)
			(layer "F.SilkS")
		)
		(fp_line
			(start -0.508 -0.9398)
			(end -0.508 0.9398)
			(stroke
				(width 0.1524)
				(type default)
			)
			(layer "F.SilkS")
		)
		(fp_rect
			(start -0.508 0.9398)
			(end 0.508 -0.9398)
			(stroke
				(width 0)
				(type default)
			)
			(fill no)
			(layer "F.CrtYd")
		)
		(fp_rect
			(start -0.508 0.9398)
			(end 0.508 -0.9398)
			(stroke
				(width 0)
				(type default)
			)
			(fill no)
			(layer "F.Fab")
		)
		(pad "1" smd custom
			(at 0 -0.4445 90)
			(size 0.1397 0.1397)
			(layers "F.Cu" "F.Mask" "F.Paste")
			(net "P12VU_2490_GATE_DRV_2")
			(options
				(clearance outline)
				(anchor circle)
			)
			(primitives
				(gr_poly
					(pts
						(arc
							(start -0.1778 -0.2794)
							(mid -0.249642 -0.249642)
							(end -0.2794 -0.1778)
						)
						(arc
							(start -0.2794 0.1778)
							(mid -0.249642 0.249642)
							(end -0.1778 0.2794)
						)
						(arc
							(start 0.1778 0.2794)
							(mid 0.249642 0.249642)
							(end 0.2794 0.1778)
						)
						(arc
							(start 0.2794 -0.1778)
							(mid 0.249642 -0.249642)
							(end 0.1778 -0.2794)
						)
					)
					(width 0)
					(fill yes)
				)
			)
		)
		(pad "2" smd custom
			(at 0 0.4445 90)
			(size 0.1397 0.1397)
			(layers "F.Cu" "F.Mask" "F.Paste")
			(net "P12VU_2490_GATE")
			(options
				(clearance outline)
				(anchor circle)
			)
			(primitives
				(gr_poly
					(pts
						(arc
							(start -0.1778 -0.2794)
							(mid -0.249642 -0.249642)
							(end -0.2794 -0.1778)
						)
						(arc
							(start -0.2794 0.1778)
							(mid -0.249642 0.249642)
							(end -0.1778 0.2794)
						)
						(arc
							(start 0.1778 0.2794)
							(mid 0.249642 0.249642)
							(end 0.2794 0.1778)
						)
						(arc
							(start 0.2794 -0.1778)
							(mid 0.249642 -0.249642)
							(end 0.1778 -0.2794)
						)
					)
					(width 0)
					(fill yes)
				)
			)
		)
	)
)
